FILE_TYPE = CONNECTIVITY;
{Allegro Design Entry HDL 16.6-p007 (v16-6-112F) 10/10/2012}
"PAGE_NUMBER" = 200;
0"NC";
1"A_HSC_LOW";
2"AGND_HSC\g";
3"P12V_STBY\g";
4"GND\g";
5"P12V_STBY\g";
6"AGND_HSC\g";
7"P3V3_STBY\g";
8"GND\g";
9"P3V3_STBY\g";
10"GND\g";
11"GND\g";
12"AGND_HSC\g";
13"AGND_HSC\g";
14"GND\g";
15"P12V_STBY\g";
16"AGND_HSC\g";
17"P3V3_STBY\g";
18"P3V3_STBY\g";
19"GND\g";
20"GND\g";
21"P3V3_STBY\g";
22"GND\g";
23"P3V3_STBY\g";
24"P3V3_STBY\g";
25"AGND_HSC\g";
26"AGND_HSC\g";
27"GND\g";
28"P12V_STBY\g";
29"GND\g";
30"AGND_HSC\g";
31"AGND_HSC\g";
32"AGND_HSC\g";
33"AGND_HSC\g";
34"P12V_PSU\g";
35"P12V_STBY\g";
36"P3V3_STBY\g";
37"P12V_MB0_SW"VOLTAGE"+12V";
38"A_HSC_MON";
39"A_P12V_STBY_FP_TRIGGER";
40"A_P12V_STBY_FPH_GATE";
41"FM_DISABLE_FAN_N";
42"FM_UV_ADR_TRIGGER_N";
43"A_P12V_STBY_ADR_TRIGGER";
44"FM_HSC_TIMER_EXP_N";
45"IRQ_UV_DETECT_N";
46"A_P12V_STBY_FP_TRIGGER";
47"UV_HIGH_SET_N";
48"FM_OC_DETECT_N";
49"A_HSC_HSN";
50"A_HSC_HSP";
51"A_HSC_GATE1_R";
52"A_HSC_INAP";
53"A_HSC_TIMER_R";
54"P12V_HSC_SENP1"VOLTAGE"+12V";
55"A_HSC_GATE3_R";
56"A_HSC_TIMER";
57"A_HSC_GATE2_R";
58"A_HSC_MOP";
59"P12V_HSC_SENN1"VOLTAGE"+12V";
60"UV_HIGH_SET";
61"P12V_HSC_SENP0"VOLTAGE"+12V";
62"PWRGD_DSW_PWROK";
63"A_HSC_LOW_DRAIN";
64"P12V_HSC_SENN0"VOLTAGE"+12V";
65"A_HSC_C";
66"FM_OC_DETECT_EN_N";
67"A_HSC_LOW_GATE";
68"A_HSC_GATE";
69"FM_OC_DETECT_EN";
70"IRQ_OC_DETECT_N";
71"A_HSC_CSOUT";
72"A_HSC_HIGH";
73"AGND_HSC\g";
%"TTL1G126_A"
"1","(-2900,2225)","0","mstr_ttl","I103";
;
CDS_SEC"1"
MATERIAL"IC"
LOCATION"U1D1"
POWER_GROUP"GND=GND"
POWER_GROUP"VCC=P3V3_STBY"
VALUE"74HC1G126"
PART_NUMBER"A79322-001"
SEC"1"
SEC_TYPE"SOT"
ROOM"HOT_SWAP"
CDS_LOCATION"U1D1"
PACK_TYPE"SOT"
CDS_LIB"mstr_ttl";
"OE"
$PN"1"69;
"Y"
$PN"4"48;
"A"
$PN"2"70;
%"AGND0"
"1","(-1650,-350)","0","mstr_symbols","I106";
;
HDL_POWER"AGND_HSC"
ROOM"VR_P3V3"
BOM_COST"MIO_VRD_MAIN"
CDS_LIB"mstr_symbols"
VOLTAGE"0"
BODY_TYPE"PLUMBING";
"A"2;
%"RES"
"2","(-1650,-150)","0","mstr_discrete","I108";
;
CDS_SEC"1"
MATERIAL"CHIP"
TOLERANCE"1%"
WATTAGE"1/16W"
LOCATION"R9P11"
VALUE"10.0K"
CONFIG"64.1002D.6DL"
PACK_TYPE"0402"
PART_NUMBER"G21796-016"
CDS_LIB"mstr_discrete"
CDS_LOCATION"R9P11"
SEC_TYPE"0402"
SEC"1"
ROOM"HOT_SWAP";
"A"
$PN"1"39;
"B"
$PN"2"2;
%"P12V_STBY"
"1","(-1650,525)","0","mstr_symbols","I109";
;
CDS_LIB"mstr_symbols"
SIZE"1B"
VOLTAGE"12.0V"
BODY_TYPE"PLUMBING"
HDL_POWER"P12V_STBY";
"G\NAC"3;
%"GND"
"1","(-3075,-475)","0","mstr_symbols","I114";
;
VOLTAGE"0.0V"
CDS_LIB"mstr_symbols"
SIZE"1B"
BODY_TYPE"PLUMBING"
HDL_POWER"GND";
"A\NAC"4;
%"P12V_STBY"
"1","(-1975,1075)","0","mstr_symbols","I144";
;
CDS_LIB"mstr_symbols"
SIZE"1B"
VOLTAGE"12.0V"
BODY_TYPE"PLUMBING"
HDL_POWER"P12V_STBY";
"G\NAC"5;
%"AGND0"
"1","(-1975,175)","0","mstr_symbols","I147";
;
HDL_POWER"AGND_HSC"
VOLTAGE"0"
CDS_LIB"mstr_symbols"
BOM_COST"MIO_VRD_MAIN"
ROOM"VR_P3V3"
BODY_TYPE"PLUMBING";
"A"6;
%"RES"
"2","(600,1100)","0","mstr_discrete","I149";
;
CDS_SEC"1"
TOLERANCE"1%"
WATTAGE"1/16W"
LOCATION"R9P6"
VALUE"10.0K"
MATERIAL"CHIP"
PART_NUMBER"G21796-016"
PACK_TYPE"0402"
CDS_LIB"mstr_discrete"
CDS_LOCATION"R9P6"
ROOM"HOT_SWAP"
SEC"1"
SEC_TYPE"0402";
"A"
$PN"1"7;
"B"
$PN"2"42;
%"P3V3_STBY"
"1","(600,1300)","0","mstr_symbols","I150";
;
VOLTAGE"+3.3V"
SIZE"1B"
CDS_LIB"mstr_symbols"
BODY_TYPE"PLUMBING"
HDL_POWER"P3V3_STBY";
"G\NAC"7;
%"RES"
"1","(1350,1875)","0","mstr_discrete","I154";
;
CDS_SEC"1"
VALUE"10.0"
TOLERANCE"1%"
PART_NUMBER"G21796-066"
LOCATION"R1D51"
WATTAGE"1/16W"
PACK_TYPE"0402"
MATERIAL"CHIP"
CDS_LIB"mstr_discrete"
CDS_LOCATION"R1D51"
ROOM"HOT_SWAP"
SEC"1"
SEC_TYPE"0402";
"B"
$PN"2"68;
"A"
$PN"1"65;
%"CAP"
"1","(900,1675)","0","mstr_discrete","I155";
;
CDS_SEC"1"
PART_NUMBER"108427-047"
PACK_TYPE"1206"
LOCATION"C1E2"
MATERIAL"X7R"
VOLTAGE"50V"
TOLERANCE"20%"
VALUE"0.068UF"
CDS_LIB"mstr_discrete"
CDS_LOCATION"C1E2"
SEC"1"
SEC_TYPE"1206";
"A"
$PN"1"65;
"B"
$PN"2"8;
%"GND"
"1","(900,1450)","0","mstr_symbols","I156";
;
SIZE"1B"
CDS_LIB"mstr_symbols"
VOLTAGE"0.0V"
BODY_TYPE"PLUMBING"
HDL_POWER"GND";
"A\NAC"8;
%"P3V3_STBY"
"1","(-1650,2525)","0","mstr_symbols","I157";
;
VOLTAGE"+3.3V"
SIZE"1B"
CDS_LIB"mstr_symbols"
BODY_TYPE"PLUMBING"
HDL_POWER"P3V3_STBY";
"G\NAC"9;
%"RES"
"2","(-1650,2350)","0","mstr_discrete","I158";
;
CDS_SEC"1"
PART_NUMBER"G21796-016"
PACK_TYPE"0402"
MATERIAL"CHIP"
VALUE"10.0K"
LOCATION"R1D22"
TOLERANCE"1%"
WATTAGE"1/16W"
SEC_TYPE"0402"
SEC"1"
ROOM"HOT_SWAP"
CDS_LOCATION"R1D22"
CDS_LIB"mstr_discrete";
"A"
$PN"1"9;
"B"
$PN"2"48;
%"TPS3700"
"1","(-350,350)","0","mstr_vreg","I163";
;
CDS_SEC"1"
MATERIAL"IC"
LOCATION"U9P1"
PART_NUMBER"H69492-001"
CDS_LOCATION"U9P1"
SEC"1"
SEC_TYPE"SM"
PACK_TYPE"SM"
CDS_LIB"mstr_vreg"
CDS_LMAN_SYM_OUTLINE"-250,200,250,-200";
"VDD"
$PN"2"5;
"OUTB"
$PN"1"40;
"OUTA"
$PN"6"42;
"INBN"
$PN"3"39;
"INAP"
$PN"4"43;
"GND"
$PN"5"10;
%"TPS3700"
"1","(-3100,3125)","0","mstr_vreg","I170";
;
CDS_SEC"1"
MATERIAL"IC"
LOCATION"U1D2"
PART_NUMBER"H69492-001"
CDS_LOCATION"U1D2"
SEC"1"
SEC_TYPE"SM"
PACK_TYPE"SM"
CDS_LIB"mstr_vreg"
CDS_LMAN_SYM_OUTLINE"-250,200,250,-200";
"VDD"
$PN"2"15;
"OUTB"
$PN"1"70;
"OUTA"
$PN"6"67;
"INBN"
$PN"3"72;
"INAP"
$PN"4"1;
"GND"
$PN"5"14;
%"RES"
"2","(-4575,2875)","0","mstr_discrete","I174";
;
CDS_SEC"1"
WATTAGE"1/16W"
MATERIAL"CHIP"
TOLERANCE"1%"
VALUE"10.0K"
LOCATION"R1D12"
CONFIG"64.1002D.6DL"
PACK_TYPE"0402"
PART_NUMBER"G21796-016"
ROOM"HOT_SWAP"
CDS_LOCATION"R1D12"
SEC"1"
SEC_TYPE"0402"
CDS_LIB"mstr_discrete";
"A"
$PN"1"1;
"B"
$PN"2"13;
%"RES"
"2","(-4150,2450)","0","mstr_discrete","I175";
;
CDS_SEC"1"
WATTAGE"1/16W"
CONFIG"64.1002D.6DL"
PACK_TYPE"0402"
PART_NUMBER"G21796-016"
MATERIAL"CHIP"
TOLERANCE"1%"
VALUE"10.0K"
LOCATION"R1D19"
CDS_LIB"mstr_discrete"
ROOM"HOT_SWAP"
CDS_LOCATION"R1D19"
SEC"1"
SEC_TYPE"0402";
"A"
$PN"1"72;
"B"
$PN"2"12;
%"GND"
"1","(-50,50)","0","mstr_symbols","I178";
;
VOLTAGE"0.0V"
CDS_LIB"mstr_symbols"
SIZE"1B"
BODY_TYPE"PLUMBING"
HDL_POWER"GND";
"A\NAC"10;
%"GND"
"1","(550,-400)","0","mstr_symbols","I179";
;
VOLTAGE"0.0V"
SIZE"1B"
CDS_LIB"mstr_symbols"
BODY_TYPE"PLUMBING"
HDL_POWER"GND";
"A\NAC"11;
%"AGND0"
"1","(-4150,2225)","0","mstr_symbols","I180";
;
HDL_POWER"AGND_HSC"
VOLTAGE"0"
BOM_COST"MIO_VRD_MAIN"
CDS_LIB"mstr_symbols"
ROOM"VR_P3V3"
BODY_TYPE"PLUMBING";
"A"12;
%"AGND0"
"1","(-4575,2500)","0","mstr_symbols","I181";
;
HDL_POWER"AGND_HSC"
ROOM"VR_P3V3"
CDS_LIB"mstr_symbols"
BOM_COST"MIO_VRD_MAIN"
VOLTAGE"0"
BODY_TYPE"PLUMBING";
"A"13;
%"GND"
"1","(-2750,2800)","0","mstr_symbols","I183";
;
VOLTAGE"0.0V"
SIZE"1B"
CDS_LIB"mstr_symbols"
BODY_TYPE"PLUMBING"
HDL_POWER"GND";
"A\NAC"14;
%"P12V_STBY"
"1","(-3800,3700)","0","mstr_symbols","I184";
;
VOLTAGE"12.0V"
CDS_LIB"mstr_symbols"
SIZE"1B"
BODY_TYPE"PLUMBING"
HDL_POWER"P12V_STBY";
"G\NAC"15;
%"CAP_A"
"1","(-825,775)","2","dev_discrete","I185";
;
MATERIAL"X7R"
LOCATION"C9P6"
VALUE"0.1UF"
TOLERANCE"10%"
PACK_TYPE"0402V"
PART_NUMBER"A36096-030"
VOLTAGE"16V"
SEC_TYPE"0402V"
SEC"1"
CDS_SEC"1"
CDS_LIB"dev_discrete"
CDS_LOCATION"C9P6"
ROOM"HOT_SWAP";
"B"
$PN"2"73;
"A"
$PN"1"5;
%"AGND0"
"1","(-825,625)","0","mstr_symbols","I186";
;
HDL_POWER"AGND_HSC"
ROOM"VR_P3V3"
BOM_COST"MIO_VRD_MAIN"
CDS_LIB"mstr_symbols"
VOLTAGE"0"
BODY_TYPE"PLUMBING";
"A"73;
%"CAP_A"
"1","(-3800,3425)","2","dev_discrete","I187";
;
VOLTAGE"16V"
MATERIAL"X7R"
TOLERANCE"10%"
VALUE"0.1UF"
LOCATION"C1D9"
PACK_TYPE"0402V"
PART_NUMBER"A36096-030"
CDS_LOCATION"C1D9"
CDS_LIB"dev_discrete"
CDS_SEC"1"
ROOM"HOT_SWAP"
SEC_TYPE"0402V"
SEC"1";
"B"
$PN"2"16;
"A"
$PN"1"15;
%"AGND0"
"1","(-3800,3175)","0","mstr_symbols","I188";
;
HDL_POWER"AGND_HSC"
BOM_COST"MIO_VRD_MAIN"
ROOM"VR_P3V3"
VOLTAGE"0"
CDS_LIB"mstr_symbols"
BODY_TYPE"PLUMBING";
"A"16;
%"P3V3_STBY"
"1","(-2600,3850)","0","mstr_symbols","I190";
;
VOLTAGE"+3.3V"
SIZE"1B"
CDS_LIB"mstr_symbols"
BODY_TYPE"PLUMBING"
HDL_POWER"P3V3_STBY";
"G\NAC"17;
%"RES"
"2","(-2950,3550)","0","mstr_discrete","I191";
;
CDS_SEC"1"
TOLERANCE"1%"
MATERIAL"CHIP"
PACK_TYPE"0402"
PART_NUMBER"G21796-016"
WATTAGE"1/16W"
VALUE"10.0K"
LOCATION"R1D23"
ROOM"HOT_SWAP"
CDS_LOCATION"R1D23"
SEC"1"
SEC_TYPE"0402"
CDS_LIB"mstr_discrete";
"A"
$PN"1"17;
"B"
$PN"2"70;
%"RES"
"2","(275,1075)","0","mstr_discrete","I192";
;
CDS_SEC"1"
LOCATION"R9P10"
PACK_TYPE"0402"
WATTAGE"1/16W"
MATERIAL"CHIP"
VALUE"10.0K"
TOLERANCE"1%"
PART_NUMBER"G21796-016"
CDS_LIB"mstr_discrete"
ROOM"HOT_SWAP"
CDS_LOCATION"R9P10"
SEC"1"
SEC_TYPE"0402";
"A"
$PN"1"18;
"B"
$PN"2"40;
%"P3V3_STBY"
"1","(275,1300)","0","mstr_symbols","I194";
;
VOLTAGE"+3.3V"
SIZE"1B"
CDS_LIB"mstr_symbols"
BODY_TYPE"PLUMBING"
HDL_POWER"P3V3_STBY";
"G\NAC"18;
%"FET_N_DUAL"
"5","(-2000,3325)","0","mstr_discrete","I196";
;
CDS_SEC"1"
MATERIAL"FET"
PART_NUMBER"D24280-001"
LOCATION"Q9P1"
VALUE"2N7002DW"
PACK_TYPE"SMLF"
SEC_TYPE"SMLF"
SEC"1"
CDS_LOCATION"Q9P1"
ROOM"HOT_SWAP"
CDS_LIB"mstr_discrete";
"GATE <SIZE -1..0>"
$PN"2"67;
"SOURCE <SIZE-1..0>"
$PN"1"19;
"DRAIN <SIZE -1..0>"
$PN"6"63;
%"GND"
"1","(-2000,3025)","0","mstr_symbols","I197";
;
VOLTAGE"0.0V"
SIZE"1B"
CDS_LIB"mstr_symbols"
BODY_TYPE"PLUMBING"
HDL_POWER"GND";
"A\NAC"19;
%"FET_N_DUAL"
"5","(550,-100)","0","mstr_discrete","I199";
;
CDS_SEC"2"
PART_NUMBER"D24280-001"
LOCATION"Q9P1"
MATERIAL"FET"
VALUE"2N7002DW"
CDS_LIB"mstr_discrete"
CDS_LOCATION"Q9P1"
PACK_TYPE"SMLF"
ROOM"HOT_SWAP"
SEC"2"
SEC_TYPE"SMLF";
"GATE <SIZE -1..0>"
$PN"5"40;
"SOURCE <SIZE-1..0>"
$PN"4"11;
"DRAIN <SIZE -1..0>"
$PN"3"45;
%"TPS3700"
"1","(-3425,-150)","0","mstr_vreg","I200";
;
LOCATION"U9P2"
PART_NUMBER"H69492-001"
MATERIAL"IC"
CDS_LMAN_SYM_OUTLINE"-250,200,250,-200"
CDS_LIB"mstr_vreg"
CDS_LOCATION"U9P2"
$SEC"1"
CDS_SEC"1"
PACK_TYPE"SM";
"VDD"
$PN"2"36;
"OUTB"
$PN"1"44;
"OUTA"
$PN"6"62;
"INBN"
$PN"3"53;
"INAP"
$PN"4"52;
"GND"
$PN"5"4;
%"CAP_A"
"1","(-3450,500)","2","dev_discrete","I201";
;
LOCATION"C9P11"
VOLTAGE"16V"
PART_NUMBER"A36096-030"
PACK_TYPE"0402V"
TOLERANCE"10%"
MATERIAL"X7R"
VALUE"0.1UF"
CDS_LIB"dev_discrete"
ROOM"HOT_SWAP"
CDS_LOCATION"C9P11"
CDS_SEC"1"
SEC_TYPE"0402V"
SEC"1";
"B"
$PN"2"20;
"A"
$PN"1"36;
%"GND"
"1","(-3450,225)","0","mstr_symbols","I202";
;
VOLTAGE"0.0V"
SIZE"1B"
CDS_LIB"mstr_symbols"
BODY_TYPE"PLUMBING"
HDL_POWER"GND";
"A\NAC"20;
%"FET_N"
"8","(-3500,1300)","0","mstr_discrete","I203";
;
CDS_SEC"1"
LOCATION"Q1D2"
MATERIAL"FET"
VALUE"2N7002"
PART_NUMBER"C79254-001"
CDS_LIB"mstr_discrete"
CDS_LOCATION"Q1D2"
SEC"1"
SEC_TYPE"SOT23LF"
ROOM"HOT_SWAP"
PACK_TYPE"SOT23LF";
"GATE"
$PN"1"66;
"DRN"
$PN"3"69;
"SRC"
$PN"2"22;
%"RES"
"2","(-3500,1750)","0","mstr_discrete","I204";
;
CDS_SEC"1"
TOLERANCE"1%"
MATERIAL"CHIP"
VALUE"4.75K"
LOCATION"R1D21"
PACK_TYPE"0402"
WATTAGE"1/16W"
PART_NUMBER"G21796-072"
CDS_LIB"mstr_discrete"
CDS_LOCATION"R1D21"
SEC_TYPE"0402"
SEC"1"
ROOM"HOT_SWAP";
"A"
$PN"1"21;
"B"
$PN"2"69;
%"P3V3_STBY"
"1","(-3500,1950)","0","mstr_symbols","I205";
;
VOLTAGE"3.3V"
CDS_LIB"mstr_symbols"
SIZE"1B"
BODY_TYPE"PLUMBING"
HDL_POWER"P3V3_STBY";
"G\NAC"21;
%"GND"
"1","(-3500,925)","0","mstr_symbols","I206";
;
CDS_LIB"mstr_symbols"
SIZE"1B"
VOLTAGE"0.0V"
BODY_TYPE"PLUMBING"
HDL_POWER"GND";
"A\NAC"22;
%"RES"
"2","(1750,225)","0","mstr_discrete","I210";
;
CDS_SEC"1"
MATERIAL"CHIP"
PACK_TYPE"0402"
PART_NUMBER"G21796-344"
TOLERANCE"1%"
WATTAGE"1/16W"
LOCATION"R9P4"
VALUE"2.7K"
CDS_LIB"mstr_discrete"
ROOM"HOT_SWAP"
CDS_LOCATION"R9P4"
SEC"1"
SEC_TYPE"0402";
"A"
$PN"1"23;
"B"
$PN"2"45;
%"P3V3_STBY"
"1","(1750,450)","0","mstr_symbols","I211";
;
CDS_LIB"mstr_symbols"
SIZE"1B"
VOLTAGE"+3.3V"
BODY_TYPE"PLUMBING"
HDL_POWER"P3V3_STBY";
"G\NAC"23;
%"DIODE"
"1","(1000,675)","2","mstr_discrete","I213";
;
CDS_SEC"1"
PART_NUMBER"C73510-001"
PACK_TYPE"SMLF"
MATERIAL"IC"
LOCATION"CR9P2"
VALUE"BAT54WS"
CDS_LOCATION"CR9P2"
SEC"1"
SEC_TYPE"SMLF"
CDS_LIB"mstr_discrete";
"C"
$PN"1"42;
"A"
$PN"2"41;
%"DIODE"
"1","(1050,175)","2","mstr_discrete","I214";
;
CDS_SEC"1"
LOCATION"CR9P1"
VALUE"BAT54WS"
POP"NOPOP"
PACK_TYPE"SMLF"
MATERIAL"IC"
PART_NUMBER"C73510-001"
CDS_LOCATION"CR9P1"
SEC"1"
SEC_TYPE"SMLF"
CDS_LIB"mstr_discrete";
"C"
$PN"1"45;
"A"
$PN"2"41;
%"RES"
"2","(1500,1125)","0","mstr_discrete","I215";
;
CDS_SEC"1"
MATERIAL"CHIP"
TOLERANCE"1%"
VALUE"10.0K"
LOCATION"R9P5"
PART_NUMBER"G21796-016"
WATTAGE"1/16W"
PACK_TYPE"0402"
CDS_LIB"mstr_discrete"
ROOM"HOT_SWAP"
CDS_LOCATION"R9P5"
SEC"1"
SEC_TYPE"0402";
"A"
$PN"1"24;
"B"
$PN"2"41;
%"P3V3_STBY"
"1","(1500,1400)","0","mstr_symbols","I216";
;
CDS_LIB"mstr_symbols"
SIZE"1B"
VOLTAGE"+3.3V"
BODY_TYPE"PLUMBING"
HDL_POWER"P3V3_STBY";
"G\NAC"24;
%"AGND0"
"1","(-4400,-650)","0","mstr_symbols","I217";
;
HDL_POWER"AGND_HSC"
VOLTAGE"0"
BOM_COST"MIO_VRD_MAIN"
CDS_LIB"mstr_symbols"
ROOM"VR_P3V3"
BODY_TYPE"PLUMBING";
"A"25;
%"RES"
"2","(-3950,-475)","0","mstr_discrete","I218";
;
CDS_SEC"1"
MATERIAL"CHIP"
PACK_TYPE"0402"
PART_NUMBER"G21796-013"
TOLERANCE"1%"
WATTAGE"1/16W"
VALUE"4.99K"
LOCATION"R9P12"
ROOM"HOT_SWAP"
CDS_LIB"mstr_discrete"
CDS_LOCATION"R9P12"
SEC"1"
SEC_TYPE"0402";
"A"
$PN"1"52;
"B"
$PN"2"26;
%"AGND0"
"1","(-3950,-675)","0","mstr_symbols","I219";
;
HDL_POWER"AGND_HSC"
ROOM"VR_P3V3"
BOM_COST"MIO_VRD_MAIN"
VOLTAGE"0"
CDS_LIB"mstr_symbols"
BODY_TYPE"PLUMBING";
"A"26;
%"DIODE"
"1","(2750,3275)","1","mstr_discrete","I220";
;
CDS_SEC"1"
CDS_LOCATION"CR1F5"
LOCATION"CR1F5"
PACK_TYPE"SM"
VALUE"MBRS340T3G"
MATERIAL"EMPTY"
PART_NUMBER"C81983-002"
CDS_LIB"mstr_discrete"
SEC_TYPE"SM"
SEC"1";
"C"
$PN"1"35;
"A"
$PN"2"27;
%"GND"
"1","(2750,3000)","0","mstr_symbols","I221";
;
CDS_LIB"mstr_symbols"
SIZE"1B"
VOLTAGE"0.0V"
BODY_TYPE"PLUMBING"
HDL_POWER"GND";
"A\NAC"27;
%"RES"
"2","(-3950,200)","2","mstr_discrete","I222";
;
CDS_LOCATION"R9P33"
WATTAGE"1/16W"
MATERIAL"CHIP"
PACK_TYPE"0402"
VALUE"100.0K"
PART_NUMBER"G21796-010"
TOLERANCE"1%"
LOCATION"R9P33"
CDS_LIB"mstr_discrete"
ROOM"HOT_SWAP"
$SEC"1"
CDS_SEC"1";
"A"
$PN"1"28;
"B"
$PN"2"52;
%"P12V_STBY"
"1","(-3950,700)","0","mstr_symbols","I223";
;
CDS_LIB"mstr_symbols"
SIZE"1B"
VOLTAGE"12.0V"
BODY_TYPE"PLUMBING"
HDL_POWER"P12V_STBY";
"G\NAC"28;
%"FET_N"
"8","(-1500,1675)","0","mstr_discrete","I225";
;
CDS_SEC"1"
$SEC"1"
CDS_LOCATION"Q6W1"
PART_NUMBER"C79254-001"
LOCATION"Q6W1"
VALUE"2N7002"
MATERIAL"FET"
CDS_LIB"mstr_discrete"
ROOM"HOT_SWAP"
PACK_TYPE"SOT23LF";
"GATE"
$PN"1"60;
"DRN"
$PN"3"47;
"SRC"
$PN"2"29;
%"GND"
"1","(-1500,1300)","0","mstr_symbols","I227";
;
SIZE"1B"
VOLTAGE"0.0V"
CDS_LIB"mstr_symbols"
BODY_TYPE"PLUMBING"
HDL_POWER"GND";
"A\NAC"29;
%"SC22P50V2JN-4GP"
"1","(-700,-100)","0","w_hdl","I235";
;
CDS_SEC"1"
CDS_LOCATION"C9W1"
TOLERANCE"5%"
LOCATION"C9W1"
RATED"50V"
POP"NOPOP"
PACK_SIZE"0402"
TYPE"NPO"
VALUE"SC22P50V2JN-4GP"
ATTRIBUTE"22PF"
CDS_LMAN_SYM_OUTLINE"-50,25,50,-25"
CDS_LIB"w_hdl"
PART_NUMBER"78.22034.1FL"
PACK_TYPE"SMD-BCG"
SEC"1"
SEC_TYPE"SMD-BCG";
"2"
$PN"2"30;
"1"
$PN"1"39;
%"SC22P50V2JN-4GP"
"1","(-1050,175)","0","w_hdl","I236";
;
CDS_SEC"1"
CDS_LOCATION"C9W2"
TYPE"NPO"
ATTRIBUTE"22PF"
RATED"50V"
PACK_SIZE"0402"
POP"NOPOP"
LOCATION"C9W2"
VALUE"SC22P50V2JN-4GP"
TOLERANCE"5%"
PART_NUMBER"78.22034.1FL"
CDS_LIB"w_hdl"
CDS_LMAN_SYM_OUTLINE"-50,25,50,-25"
PACK_TYPE"SMD-BCG"
SEC"1"
SEC_TYPE"SMD-BCG";
"2"
$PN"2"31;
"1"
$PN"1"43;
%"AGND0"
"1","(-700,-250)","0","mstr_symbols","I237";
;
HDL_POWER"AGND_HSC"
ROOM"VR_P3V3"
BOM_COST"MIO_VRD_MAIN"
VOLTAGE"0"
CDS_LIB"mstr_symbols"
BODY_TYPE"PLUMBING";
"A"30;
%"AGND0"
"1","(-1050,-100)","0","mstr_symbols","I238";
;
HDL_POWER"AGND_HSC"
CDS_LIB"mstr_symbols"
ROOM"VR_P3V3"
BOM_COST"MIO_VRD_MAIN"
VOLTAGE"0"
BODY_TYPE"PLUMBING";
"A"31;
%"RES"
"1","(-1750,3800)","0","mstr_discrete","I243";
;
CDS_SEC"1"
CDS_LOCATION"R9P15"
VALUE"0.0"
LOCATION"R9P15"
WATTAGE"1/16W"
TOLERANCE"5%"
PACK_TYPE"0402"
MATERIAL"CHIP"
PART_NUMBER"G21497-005"
SEC"1"
SEC_TYPE"0402"
CDS_LIB"mstr_discrete";
"B"
$PN"2"70;
"A"
$PN"1"63;
%"RES"
"2","(-2600,3550)","0","mstr_discrete","I244";
;
CDS_SEC"1"
WATTAGE"1/16W"
MATERIAL"CHIP"
LOCATION"R1D10"
VALUE"10.0K"
TOLERANCE"1%"
PACK_TYPE"0402"
PART_NUMBER"G21796-016"
ROOM"HOT_SWAP"
SEC"1"
SEC_TYPE"0402"
CDS_LIB"mstr_discrete"
CDS_LOCATION"R1D10";
"A"
$PN"1"17;
"B"
$PN"2"67;
%"RES"
"2","(-4575,3450)","0","mstr_discrete","I246";
;
WATTAGE"1/16W"
TOLERANCE"1%"
PACK_TYPE"0402"
BOM_SS"64.16535.6DL"
LOCATION"R1D14"
VALUE"105.0K"
MATERIAL"CHIP"
BOM_DS"64.15435.6DL"
PART_NUMBER"G21796-099"
SEC_TYPE"0402"
SEC"1"
CDS_LOCATION"R1D14"
CDS_LIB"mstr_discrete"
CDS_SEC"1";
"A"
$PN"1"71;
"B"
$PN"2"1;
%"270KR2F-GP"
"1","(-1650,275)","0","w_hdl","I249";
;
CDS_SEC"1"
CDS_LOCATION"R9P13"
LOCATION"R9P13"
VALUE"270KR2F-GP"
RATED"1/16W"
PACK_SIZE"0402"
ATTRIBUTE"270KOHM"
TOLERANCE"1%"
PACK_TYPE"RCL_GP"
SEC"1"
SEC_TYPE"RCL_GP"
PART_NUMBER"64.27035.6DL"
CDS_LIB"w_hdl"
CDS_LMAN_SYM_OUTLINE"-50,75,50,-75";
"2"
$PN"2"39;
"1"
$PN"1"3;
%"232KR2F-2-GP"
"1","(-800,1950)","1","w_hdl","I250";
;
CDS_SEC"1"
CDS_LOCATION"R6W3"
VALUE"232KR2F-2-GP"
PACK_SIZE"0402"
TOLERANCE"1%"
RATED"1/16W"
LOCATION"R6W3"
ATTRIBUTE"232KOHM"
PACK_TYPE"SMD-RG1"
SEC"1"
SEC_TYPE"SMD-RG1"
PART_NUMBER"64.23235.L0L"
CDS_LIB"w_hdl"
CDS_LMAN_SYM_OUTLINE"-50,75,50,-75";
"2"
$PN"2"46;
"1"
$PN"1"47;
%"RES"
"2","(-1975,375)","0","mstr_discrete","I251";
;
PART_NUMBER"G21796-059"
MATERIAL"CHIP"
WATTAGE"1/16W"
TOLERANCE"1%"
VALUE"3.74K"
PACK_TYPE"0402"
LOCATION"R9P9"
SEC"1"
SEC_TYPE"0402"
ROOM"V_SUPER"
CDS_LIB"mstr_discrete"
CDS_SEC"1"
CDS_LOCATION"R9P9";
"A"
$PN"1"43;
"B"
$PN"2"6;
%"RES"
"2","(-1975,800)","0","mstr_discrete","I252";
;
MATERIAL"CHIP"
TOLERANCE"1%"
LOCATION"R9P7"
VALUE"100.0K"
WATTAGE"1/16W"
PACK_TYPE"0402"
PART_NUMBER"G21796-010"
SEC"1"
SEC_TYPE"0402"
ROOM"V_SUPER"
CDS_LIB"mstr_discrete"
CDS_SEC"1"
CDS_LOCATION"R9P7";
"A"
$PN"1"5;
"B"
$PN"2"43;
%"RES"
"2","(-4150,2825)","0","mstr_discrete","I253";
;
CDS_SEC"1"
WATTAGE"1/16W"
TOLERANCE"1%"
LOCATION"R1D20"
VALUE"200.0K"
MATERIAL"CHIP"
PACK_TYPE"0402"
PART_NUMBER"G21796-080"
BOM_DS"64.16935.6DL"
ROOM"BMC_VOLT_MONITOR"
SEC"1"
BOM_COST"SM_HM"
SEC_TYPE"0402"
CDS_LIB"mstr_discrete"
CDS_LOCATION"R1D20";
"A"
$PN"1"71;
"B"
$PN"2"72;
%"CAP_A"
"1","(-1025,3425)","0","dev_discrete","I36";
;
CDS_SEC"1"
VALUE"0.1UF"
MATERIAL"EMPTY"
VOLTAGE"16V"
LOCATION"C9P17"
TOLERANCE"10%"
PART_NUMBER"A36096-030"
PACK_TYPE"0402V"
CDS_LIB"dev_discrete"
CDS_LOCATION"C9P17"
ROOM"HOT_SWAP"
SEC_TYPE"0402V"
SEC"1";
"B"
$PN"2"32;
"A"
$PN"1"38;
%"AGND0"
"1","(-1025,3225)","0","mstr_symbols","I39";
;
HDL_POWER"AGND_HSC"
ROOM"VR_P3V3"
VOLTAGE"0"
CDS_LIB"mstr_symbols"
BOM_COST"MIO_VRD_MAIN"
BODY_TYPE"PLUMBING";
"A"32;
%"CAP_A"
"1","(-675,3000)","0","dev_discrete","I40";
;
$SEC"1"
PART_NUMBER"A36096-030"
TOLERANCE"10%"
MATERIAL"EMPTY"
VALUE"0.1UF"
VOLTAGE"16V"
LOCATION"C9P16"
PACK_TYPE"0402V"
CDS_LIB"dev_discrete"
ROOM"HOT_SWAP"
CDS_LOCATION"C9P16"
CDS_SEC"1";
"B"
$PN"2"33;
"A"
$PN"1"58;
%"AGND0"
"1","(-675,2725)","0","mstr_symbols","I41";
;
HDL_POWER"AGND_HSC"
ROOM"VR_P3V3"
BOM_COST"MIO_VRD_MAIN"
CDS_LIB"mstr_symbols"
VOLTAGE"0"
BODY_TYPE"PLUMBING";
"A"33;
%"CAP_A"
"1","(-175,3425)","0","dev_discrete","I42";
;
$SEC"1"
PART_NUMBER"A36096-030"
VOLTAGE"16V"
TOLERANCE"10%"
PACK_TYPE"0402V"
MATERIAL"EMPTY"
LOCATION"C1D22"
VALUE"0.1UF"
CDS_LIB"dev_discrete"
CDS_LOCATION"C1D22"
ROOM"HOT_SWAP"
CDS_SEC"1";
"B"
$PN"2"58;
"A"
$PN"1"38;
%"RES"
"1","(250,3625)","0","mstr_discrete","I43";
;
LOCATION"R1D45"
TOLERANCE"5%"
MATERIAL"CHIP"
VALUE"0.0"
PACK_TYPE"0402"
PART_NUMBER"G21497-005"
WATTAGE"1/16W"
$SEC"1"
CDS_SEC"1"
CDS_LIB"mstr_discrete"
CDS_LOCATION"R1D45"
ROOM"HOT_SWAP";
"B"
$PN"2"49;
"A"
$PN"1"38;
%"RES"
"1","(225,3150)","0","mstr_discrete","I44";
;
PACK_TYPE"0402"
WATTAGE"1/16W"
VALUE"0.0"
PART_NUMBER"G21497-005"
MATERIAL"CHIP"
LOCATION"R1D44"
TOLERANCE"5%"
CDS_LIB"mstr_discrete"
CDS_LOCATION"R1D44"
ROOM"HOT_SWAP"
$SEC"1"
CDS_SEC"1";
"B"
$PN"2"50;
"A"
$PN"1"58;
%"RES"
"2","(875,2800)","0","mstr_discrete","I47";
;
VALUE"10.0"
PART_NUMBER"G21796-066"
PACK_TYPE"0402"
MATERIAL"CHIP"
TOLERANCE"1%"
WATTAGE"1/16W"
LOCATION"R9P27"
CDS_LIB"mstr_discrete"
CDS_SEC"1"
$SEC"1"
CDS_LOCATION"R9P27"
ROOM"HOT_SWAP";
"A"
$PN"1"54;
"B"
$PN"2"50;
%"RES"
"2","(750,2800)","2","mstr_discrete","I48";
;
WATTAGE"1/16W"
PART_NUMBER"G21796-066"
LOCATION"R1D46"
TOLERANCE"1%"
VALUE"10.0"
PACK_TYPE"0402"
MATERIAL"CHIP"
CDS_LIB"mstr_discrete"
ROOM"HOT_SWAP"
CDS_LOCATION"R1D46"
CDS_SEC"1"
$SEC"1";
"A"
$PN"1"61;
"B"
$PN"2"50;
%"RES_PWR"
"2","(1125,3200)","0","mstr_discrete","I49";
;
CDS_SEC"1"
VALUE"0.001"
PACK_TYPE"6PAD"
MATERIAL"CHIP"
TOLERANCE"1%"
LOCATION"R9R1"
PART_NUMBER"E74391-005"
BOM_DS"064.0U505.0C71"
WATTAGE"3W"
CDS_LMAN_SYM_OUTLINE"-50,100,50,-100"
CDS_LIB"mstr_discrete"
CDS_LOCATION"R9R1"
ROOM"HOT_SWAP"
SEC"1"
SEC_TYPE"6PAD";
"6"
$PN"6"37;
"5"
$PN"5"34;
"4"
$PN"4"59;
"3"
$PN"3"54;
"1"
$PN"1"34;
"2"
$PN"2"37;
%"RES_PWR"
"2","(1125,3600)","0","mstr_discrete","I50";
;
CDS_SEC"1"
MATERIAL"CHIP"
TOLERANCE"1%"
PACK_TYPE"6PAD"
VALUE"0.001"
PART_NUMBER"E74391-005"
LOCATION"R1D49"
WATTAGE"3W"
BOM_DS"064.0U505.0C71"
CDS_LIB"mstr_discrete"
CDS_LMAN_SYM_OUTLINE"-50,100,50,-100"
CDS_LOCATION"R1D49"
SEC_TYPE"6PAD"
SEC"1"
ROOM"HOT_SWAP";
"6"
$PN"6"37;
"5"
$PN"5"34;
"4"
$PN"4"64;
"3"
$PN"3"61;
"1"
$PN"1"34;
"2"
$PN"2"37;
%"RES"
"2","(1350,2800)","2","mstr_discrete","I51";
;
VALUE"10.0"
TOLERANCE"1%"
LOCATION"R9P26"
MATERIAL"CHIP"
PACK_TYPE"0402"
PART_NUMBER"G21796-066"
WATTAGE"1/16W"
CDS_LIB"mstr_discrete"
ROOM"HOT_SWAP"
CDS_LOCATION"R9P26"
$SEC"1"
CDS_SEC"1";
"A"
$PN"1"59;
"B"
$PN"2"49;
%"RES"
"2","(1475,2800)","0","mstr_discrete","I52";
;
WATTAGE"1/16W"
MATERIAL"CHIP"
PACK_TYPE"0402"
LOCATION"R1D47"
TOLERANCE"1%"
VALUE"10.0"
PART_NUMBER"G21796-066"
CDS_LIB"mstr_discrete"
CDS_SEC"1"
$SEC"1"
CDS_LOCATION"R1D47"
ROOM"HOT_SWAP";
"A"
$PN"1"64;
"B"
$PN"2"49;
%"P12V_PSU"
"1","(900,3825)","0","mstr_symbols","I53";
;
VOLTAGE"12.0"
CDS_LIB"mstr_symbols"
BOM_COST"NT_BASE_VRD"
ROOM"P2V5_LAN_AUX_VR"
BODY_TYPE"PLUMBING"
HDL_POWER"P12V_PSU";
"G\NAC"34;
%"MOSFETN_1D3S"
"1","(2275,3375)","1","mstr_discrete","I54";
;
CDS_SEC"1"
PART_NUMBER"G68777-001"
LOCATION"EU1E3"
MATERIAL"IC"
ROOM"HOT_SWAP"
CDS_LOCATION"EU1E3"
CDS_LIB"mstr_discrete"
PACK_TYPE"SOT5"
SEC_TYPE"SOT5"
SEC"1";
"D"
$PN"5"37;
"S3"
$PN"3"35;
"S1"
$PN"1"35;
"S2"
$PN"2"35;
"G"
$PN"4"51;
%"RES"
"1","(2000,3075)","0","mstr_discrete","I56";
;
CDS_SEC"1"
WATTAGE"1/16W"
LOCATION"R1E1"
PACK_TYPE"0402"
MATERIAL"CHIP"
PART_NUMBER"G21796-066"
TOLERANCE"1%"
VALUE"10.0"
ROOM"HOT_SWAP"
CDS_LOCATION"R1E1"
SEC"1"
SEC_TYPE"0402"
CDS_LIB"mstr_discrete";
"B"
$PN"2"51;
"A"
$PN"1"68;
%"MOSFETN_1D3S"
"1","(2300,2825)","1","mstr_discrete","I57";
;
CDS_SEC"1"
PART_NUMBER"G68777-001"
MATERIAL"IC"
LOCATION"EU9R1"
CDS_LIB"mstr_discrete"
CDS_LOCATION"EU9R1"
ROOM"HOT_SWAP"
PACK_TYPE"SOT5"
SEC_TYPE"SOT5"
SEC"1";
"D"
$PN"5"37;
"S3"
$PN"3"35;
"S1"
$PN"1"35;
"S2"
$PN"2"35;
"G"
$PN"4"57;
%"RES"
"1","(2000,2525)","0","mstr_discrete","I58";
;
PACK_TYPE"0402"
VALUE"10.0"
TOLERANCE"1%"
PART_NUMBER"G21796-066"
MATERIAL"CHIP"
LOCATION"R9R4"
WATTAGE"1/16W"
CDS_LIB"mstr_discrete"
CDS_SEC"1"
CDS_LOCATION"R9R4"
$SEC"1"
ROOM"HOT_SWAP";
"B"
$PN"2"57;
"A"
$PN"1"68;
%"MOSFETN_1D3S"
"1","(2275,2100)","1","mstr_discrete","I59";
;
CDS_SEC"1"
LOCATION"EU1E1"
PART_NUMBER"G68777-001"
MATERIAL"IC"
CDS_LIB"mstr_discrete"
CDS_LOCATION"EU1E1"
ROOM"HOT_SWAP"
PACK_TYPE"SOT5"
SEC_TYPE"SOT5"
SEC"1";
"D"
$PN"5"37;
"S3"
$PN"3"35;
"S1"
$PN"1"35;
"S2"
$PN"2"35;
"G"
$PN"4"55;
%"RES"
"1","(1950,1775)","0","mstr_discrete","I60";
;
CDS_SEC"1"
PART_NUMBER"G21796-066"
LOCATION"R1D48"
TOLERANCE"1%"
VALUE"10.0"
PACK_TYPE"0402"
MATERIAL"CHIP"
WATTAGE"1/16W"
ROOM"HOT_SWAP"
CDS_LOCATION"R1D48"
SEC"1"
SEC_TYPE"0402"
CDS_LIB"mstr_discrete";
"B"
$PN"2"55;
"A"
$PN"1"68;
%"P12V_STBY"
"1","(2525,3800)","0","mstr_symbols","I64";
;
VOLTAGE"12.0V"
CDS_LIB"mstr_symbols"
SIZE"1B"
BODY_TYPE"PLUMBING"
HDL_POWER"P12V_STBY";
"G\NAC"35;
%"RES"
"2","(-4400,-400)","0","mstr_discrete","I70";
;
CDS_SEC"1"
PACK_TYPE"0402"
WATTAGE"1/16W"
TOLERANCE"1%"
VALUE"10.0K"
LOCATION"R9P19"
MATERIAL"EMPTY"
PART_NUMBER"G21796-016"
CDS_LIB"mstr_discrete"
CDS_LOCATION"R9P19"
ROOM"HOT_SWAP"
SEC"1"
SEC_TYPE"0402";
"A"
$PN"1"53;
"B"
$PN"2"25;
%"RES"
"2","(-4400,250)","0","mstr_discrete","I71";
;
CDS_SEC"1"
PACK_TYPE"0402"
VALUE"0.0"
LOCATION"R9P21"
TOLERANCE"5%"
PART_NUMBER"G21497-005"
WATTAGE"1/16W"
MATERIAL"CHIP"
CDS_LIB"mstr_discrete"
CDS_LOCATION"R9P21"
SEC"1"
ROOM"HOT_SWAP"
SEC_TYPE"0402";
"A"
$PN"1"56;
"B"
$PN"2"53;
%"P3V3_STBY"
"1","(-3300,800)","0","mstr_symbols","I78";
;
VOLTAGE"3.3V"
SIZE"1B"
CDS_LIB"mstr_symbols"
BODY_TYPE"PLUMBING"
HDL_POWER"P3V3_STBY";
"G\NAC"36;
%"RES"
"2","(-3300,450)","0","mstr_discrete","I86";
;
CDS_SEC"1"
LOCATION"R9P20"
WATTAGE"1/16W"
MATERIAL"CHIP"
PACK_TYPE"0402"
TOLERANCE"1%"
PART_NUMBER"G21796-344"
VALUE"2.7K"
CDS_LIB"mstr_discrete"
CDS_LOCATION"R9P20"
ROOM"HOT_SWAP"
SEC_TYPE"0402"
SEC"1";
"A"
$PN"1"36;
"B"
$PN"2"44;
END.
